# S9S_MB_2U (Grand Teton) — schematic netlist excerpt (pin names and nets, part order shuffled) for the footprints in the layout excerpt that follows; sources: Cadence DE-HDL packaged netlist, KiCad conversion of 03242023_DA0F0TMBIJ0_F0T_Motherboard_J_brd_V01_OCP.brd

J6  SCONN288_ADR50017P087CC  SCONN288_ADR50017-P087CC IO  pkg DDR288S_1-1VXB  page 87
  VIN_BULK0  = P12V_S3_AUX_CPU0_NVDIMM
  RFU0  = TP_CHC_CPU0_DIMM2_FRU_0
  VIN_MGMT  = P3V3_AUX
  HSCL  = I3C_SPD_DDRABCD_CPU0_LVC1_SCL_5
  HSDA  = I3C_SPD_DDRABCD_CPU0_LVC1_SDA
  VSS0  = GND
  DQ0_A  = M_C_CPU0_SA_DQ<0>
  VSS1  = GND
  DQ1_A  = M_C_CPU0_SA_DQ<1>
  VSS2  = GND
  DQS0_A_T  = M_C_CPU0_SA_DQS_DP<0>
  DQS0_A_C  = M_C_CPU0_SA_DQS_DN<0>
  VSS3  = GND
  DQ4_A  = M_C_CPU0_SA_DQ<4>
  VSS4  = GND
  DQ5_A  = M_C_CPU0_SA_DQ<5>
  VSS5  = GND
  DQ8_A  = M_C_CPU0_SA_DQ<8>
  VSS6  = GND
  DQ9_A  = M_C_CPU0_SA_DQ<9>
  VSS7  = GND
  DQS1_A_T  = M_C_CPU0_SA_DQS_DP<1>
  DQS1_A_C  = M_C_CPU0_SA_DQS_DN<1>
  VSS8  = GND
  DQ12_A  = M_C_CPU0_SA_DQ<12>
  VSS9  = GND
  DQ13_A  = M_C_CPU0_SA_DQ<13>
  VSS10  = GND
  DQ16_A  = M_C_CPU0_SA_DQ<16>
  VSS11  = GND
  DQ17_A  = M_C_CPU0_SA_DQ<17>
  VSS12  = GND
  DQS2_A_T  = M_C_CPU0_SA_DQS_DP<2>
  DQS2_A_C  = M_C_CPU0_SA_DQS_DN<2>
  VSS13  = GND
  DQ20_A  = M_C_CPU0_SA_DQ<20>
  VSS14  = GND
  DQ21_A  = M_C_CPU0_SA_DQ<21>
  VSS15  = GND
  DQ24_A  = M_C_CPU0_SA_DQ<24>
  VSS16  = GND
  DQ25_A  = M_C_CPU0_SA_DQ<25>
  VSS17  = GND
  DQS3_A_T  = M_C_CPU0_SA_DQS_DP<3>
  DQS3_A_C  = M_C_CPU0_SA_DQS_DN<3>
  VSS18  = GND
  DQ28_A  = M_C_CPU0_SA_DQ<28>
  VSS19  = GND
  DQ29_A  = M_C_CPU0_SA_DQ<29>
  VSS20  = GND
  CB0_A  = M_C_CPU0_SA_CB<0>
  VSS21  = GND
  CB1_A  = M_C_CPU0_SA_CB<1>
  VSS22  = GND
  DQS4_A_T  = M_C_CPU0_SA_DQS_DP<4>
  DQS4_A_C  = M_C_CPU0_SA_DQS_DN<4>
  VSS23  = GND
  CB4_A  = M_C_CPU0_SA_CB<4>
  VSS24  = GND
  CB5_A  = M_C_CPU0_SA_CB<5>
  VSS25  = GND
  ALERT_N  = M_C_CPU0_ALERT_N
  VSS26  = GND
  CS0_A_N  = M_C_CPU0_SA_CS_N<2>
  VSS27  = GND
  CA0_A  = M_C_CPU0_SA_CA<0>
  VSS28  = GND
  CA2_A  = M_C_CPU0_SA_CA<2>
  VSS29  = GND
  CA4_A  = M_C_CPU0_SA_CA<4>
  VSS30  = GND
  CA6_A  = M_C_CPU0_SA_CA<6>
  VSS31  = GND
  PAR_A  = M_C_CPU0_SA_PAR
  VSS32  = GND
  CA0_B  = M_C_CPU0_SB_CA<0>
  VSS33  = GND
  CA2_B  = M_C_CPU0_SB_CA<2>
  VSS34  = GND
  CA4_B  = M_C_CPU0_SB_CA<4>
  VSS35  = GND
  CA6_B  = M_C_CPU0_SB_CA<6>
  VSS36  = GND
  CS0_B_N  = M_C_CPU0_SB_CS_N<2>
  VSS37  = GND
  \lbd||rsp_a_n\  = M_C_CPU0_SA_RSP<1>
  \lbs||rsp_b_n\  = M_C_CPU0_SB_RSP<1>
  VSS38  = GND
  CB4_B  = M_C_CPU0_SB_CB<4>
  VSS39  = GND
  CB5_B  = M_C_CPU0_SB_CB<5>
  VSS40  = GND
  \dqs9_b_t||tdqs9_b_t||dbi4_b_n\  = M_C_CPU0_SB_DQS_DP<9>
  \dqs9_b_c||tdqs9_b_c\  = M_C_CPU0_SB_DQS_DN<9>
  VSS41  = GND
  CB0_B  = M_C_CPU0_SB_CB<0>
  VSS42  = GND
  CB1_B  = M_C_CPU0_SB_CB<1>
  VSS43  = GND
  DQ0_B  = M_C_CPU0_SB_DQ<0>
  VSS44  = GND
  DQ1_B  = M_C_CPU0_SB_DQ<1>
  VSS45  = GND
  DQS0_B_T  = M_C_CPU0_SB_DQS_DP<0>
  DQS0_B_C  = M_C_CPU0_SB_DQS_DN<0>
  VSS46  = GND
  DQ4_B  = M_C_CPU0_SB_DQ<4>
  VSS47  = GND
  DQ5_B  = M_C_CPU0_SB_DQ<5>
  VSS48  = GND
  DQ8_B  = M_C_CPU0_SB_DQ<8>
  VSS49  = GND
  DQ9_B  = M_C_CPU0_SB_DQ<9>
  VSS50  = GND
  DQS1_B_T  = M_C_CPU0_SB_DQS_DP<1>
  DQS1_B_C  = M_C_CPU0_SB_DQS_DN<1>
  VSS51  = GND
  DQ12_B  = M_C_CPU0_SB_DQ<12>
  VSS52  = GND
  DQ13_B  = M_C_CPU0_SB_DQ<13>
  VSS53  = GND
  DQ16_B  = M_C_CPU0_SB_DQ<16>
  VSS54  = GND
  DQ17_B  = M_C_CPU0_SB_DQ<17>
  VSS55  = GND
  DQS2_B_T  = M_C_CPU0_SB_DQS_DP<2>
  DQS2_B_C  = M_C_CPU0_SB_DQS_DN<2>
  VSS56  = GND
  DQ20_B  = M_C_CPU0_SB_DQ<20>
  VSS57  = GND
  DQ21_B  = M_C_CPU0_SB_DQ<21>
  VSS58  = GND
  DQ24_B  = M_C_CPU0_SB_DQ<24>
  VSS59  = GND
  DQ25_B  = M_C_CPU0_SB_DQ<25>
  VSS60  = GND
  DQS3_B_T  = M_C_CPU0_SB_DQS_DP<3>
  DQS3_B_C  = M_C_CPU0_SB_DQS_DN<3>
  VSS61  = GND
  DQ28_B  = M_C_CPU0_SB_DQ<28>
  VSS62  = GND
  DQ29_B  = M_C_CPU0_SB_DQ<29>
  VSS63  = GND
  RFU1  = TP_CHC_CPU0_DIMM2_FRU_1
  VIN_BULK1  = P12V_S3_AUX_CPU0_NVDIMM
  VIN_BULK2  = P12V_S3_AUX_CPU0_NVDIMM
  \pwr_good||fail_n\  = PWRGD_CHC_CPU0_DIMM2
  HSA  = PD_CHC_CPU0_DIMM2_SAA
  RFU2  = TP_CHC_CPU0_DIMM2_FRU_2
  RFU3  = TP_CHC_CPU0_DIMM2_FRU_3
  VSS64  = GND
  DQ2_A  = M_C_CPU0_SA_DQ<2>
  VSS65  = GND
  DQ3_A  = M_C_CPU0_SA_DQ<3>
  VSS66  = GND
  \dqs5_a_c||tdqs5_a_c||dqs5_a_t||tdqs5_a_t\  = M_C_CPU0_SA_DQS_DN<5>
  \dqs5_a_t||tdqs5_a_t\  = M_C_CPU0_SA_DQS_DP<5>
  VSS67  = GND
  DQ6_A  = M_C_CPU0_SA_DQ<6>
  VSS68  = GND
  DQ7_A  = M_C_CPU0_SA_DQ<7>
  VSS69  = GND
  DQ10_A  = M_C_CPU0_SA_DQ<10>
  VSS70  = GND
  DQ11_A  = M_C_CPU0_SA_DQ<11>
  VSS71  = GND
  \dqs6_a_c||tdqs6_a_c||dqs6_a_t||tdqs6_a_t\  = M_C_CPU0_SA_DQS_DN<6>
  \dqs6_a_t||tdqs6_a_t\  = M_C_CPU0_SA_DQS_DP<6>
  VSS72  = GND
  DQ14_A  = M_C_CPU0_SA_DQ<14>
  VSS73  = GND
  DQ15_A  = M_C_CPU0_SA_DQ<15>
  VSS74  = GND
  DQ18_A  = M_C_CPU0_SA_DQ<18>
  VSS75  = GND
  DQ19_A  = M_C_CPU0_SA_DQ<19>
  VSS76  = GND
  \dqs7_a_c||tdqs7_a_c\  = M_C_CPU0_SA_DQS_DN<7>
  \dqs7_a_t||tdqs7_a_t\  = M_C_CPU0_SA_DQS_DP<7>
  VSS77  = GND
  DQ22_A  = M_C_CPU0_SA_DQ<22>
  VSS78  = GND
  DQ23_A  = M_C_CPU0_SA_DQ<23>
  VSS79  = GND
  DQ26_A  = M_C_CPU0_SA_DQ<26>
  VSS80  = GND
  DQ27_A  = M_C_CPU0_SA_DQ<27>
  VSS81  = GND
  \dqs8_a_c||tdqs8_a_c\  = M_C_CPU0_SA_DQS_DN<8>
  \dqs8_a_t||tdqs8_a_t\  = M_C_CPU0_SA_DQS_DP<8>
  VSS82  = GND
  DQ30_A  = M_C_CPU0_SA_DQ<30>
  VSS83  = GND
  DQ31_A  = M_C_CPU0_SA_DQ<31>
  VSS84  = GND
  CB2_A  = M_C_CPU0_SA_CB<2>
  VSS85  = GND
  CB3_A  = M_C_CPU0_SA_CB<3>
  VSS86  = GND
  \dqs9_a_c||tdqs9_a_c\  = M_C_CPU0_SA_DQS_DN<9>
  \dqs9_a_t||tdqs9_a_t\  = M_C_CPU0_SA_DQS_DP<9>
  VSS87  = GND
  CB6_A  = M_C_CPU0_SA_CB<6>
  VSS88  = GND
  CB7_A  = M_C_CPU0_SA_CB<7>
  VSS89  = GND
  RESET_N  = RST_M_CD_CPU0_FPGA_N
  VSS90  = GND
  CS1_A_N  = M_C_CPU0_SA_CS_N<3>
  VSS91  = GND
  CA1_A  = M_C_CPU0_SA_CA<1>
  VSS92  = GND
  CA3_A  = M_C_CPU0_SA_CA<3>
  VSS93  = GND
  CA5_A  = M_C_CPU0_SA_CA<5>
  VSS94  = GND
  CK_T  = M_C_CPU0_CLK_DP<1>
  CK_C  = M_C_CPU0_CLK_DN<1>
  VSS95  = GND
  RFU4  = TP_CHC_CPU0_DIMM2_FRU_4
  CA1_B  = M_C_CPU0_SB_CA<1>
  VSS96  = GND
  CA3_B  = M_C_CPU0_SB_CA<3>
  VSS97  = GND
  CA5_B  = M_C_CPU0_SB_CA<5>
  VSS98  = GND
  PAR_B  = M_C_CPU0_SB_PAR
  VSS99  = GND
  CS1_B_N  = M_C_CPU0_SB_CS_N<3>
  VSS100  = GND
  RFU5  = TP_CHC_CPU0_DIMM2_FRU_5
  RFU6  = TP_CHC_CPU0_DIMM2_FRU_6
  VSS101  = GND
  CB6_B  = M_C_CPU0_SB_CB<6>
  VSS102  = GND
  CB7_B  = M_C_CPU0_SB_CB<7>
  VSS103  = GND
  DQS4_B_C  = M_C_CPU0_SB_DQS_DN<4>
  DQS4_B_T  = M_C_CPU0_SB_DQS_DP<4>
  VSS104  = GND
  CB2_B  = M_C_CPU0_SB_CB<2>
  VSS105  = GND
  CB3_B  = M_C_CPU0_SB_CB<3>
  VSS106  = GND
  DQ2_B  = M_C_CPU0_SB_DQ<2>
  VSS107  = GND
  DQ3_B  = M_C_CPU0_SB_DQ<3>
  VSS108  = GND
  \dqs5_b_c||tdqs5_b_c\  = M_C_CPU0_SB_DQS_DN<5>
  \dqs5_b_t||tdqs5_b_t\  = M_C_CPU0_SB_DQS_DP<5>
  VSS109  = GND
  DQ6_B  = M_C_CPU0_SB_DQ<6>
  VSS110  = GND
  DQ7_B  = M_C_CPU0_SB_DQ<7>
  VSS111  = GND
  DQ10_B  = M_C_CPU0_SB_DQ<10>
  VSS112  = GND
  DQ11_B  = M_C_CPU0_SB_DQ<11>
  VSS113  = GND
  \dqs6_b_c||tdqs6_b_c\  = M_C_CPU0_SB_DQS_DN<6>
  \dqs6_b_t||tdqs6_b_t\  = M_C_CPU0_SB_DQS_DP<6>
  VSS114  = GND
  DQ14_B  = M_C_CPU0_SB_DQ<14>
  VSS115  = GND
  DQ15_B  = M_C_CPU0_SB_DQ<15>
  VSS116  = GND
  DQ18_B  = M_C_CPU0_SB_DQ<18>
  VSS117  = GND
  DQ19_B  = M_C_CPU0_SB_DQ<19>
  VSS118  = GND
  \dqs7_b_c||tdqs7_b_c\  = M_C_CPU0_SB_DQS_DN<7>
  \dqs7_b_t||tdqs7_b_t\  = M_C_CPU0_SB_DQS_DP<7>
  VSS119  = GND
  DQ22_B  = M_C_CPU0_SB_DQ<22>
  VSS120  = GND
  DQ23_B  = M_C_CPU0_SB_DQ<23>
  VSS121  = GND
  DQ26_B  = M_C_CPU0_SB_DQ<26>
  VSS122  = GND
  DQ27_B  = M_C_CPU0_SB_DQ<27>
  VSS123  = GND
  \dqs8_b_c||tdqs8_b_c\  = M_C_CPU0_SB_DQS_DN<8>
  \dqs8_b_t||tdqs8_b_t\  = M_C_CPU0_SB_DQS_DP<8>
  VSS124  = GND
  DQ30_B  = M_C_CPU0_SB_DQ<30>
  VSS125  = GND
  DQ31_B  = M_C_CPU0_SB_DQ<31>
  VSS126  = GND
  G1  = GND
  G2  = GND
  G3  = GND

(kicad_pcb
	(version 20260206)
	(generator "pcbnew")
	(generator_version "10.0")
	(general
		(thickness 1.6)
		(legacy_teardrops no)
	)
	(paper "A4")
	(title_block
		(title "03242023_DA0F0TMBIJ0_F0T_Motherboard_J_brd_V01_OCP.brd")
		(comment 1 "Grand Teton / footprint 3553 of 6105 (J6), pads 1-45 of 291")
	)
	(layers
		(0 "F.Cu" signal "TOP")
		(4 "In1.Cu" signal "GND")
		(6 "In2.Cu" signal "IN1")
		(8 "In3.Cu" signal "GND1")
		(10 "In4.Cu" signal "IN2")
		(12 "In5.Cu" signal "GND2")
		(14 "In6.Cu" signal "IN3")
		(16 "In7.Cu" signal "GND3")
		(18 "In8.Cu" signal "VCC")
		(20 "In9.Cu" signal "VCC1")
		(22 "In10.Cu" signal "GND4")
		(24 "In11.Cu" signal "IN4")
		(26 "In12.Cu" signal "GND5")
		(28 "In13.Cu" signal "IN5")
		(30 "In14.Cu" signal "GND6")
		(32 "In15.Cu" signal "IN6")
		(34 "In16.Cu" signal "GND7")
		(2 "B.Cu" signal "BOTTOM")
		(9 "F.Adhes" user "F.Adhesive")
		(11 "B.Adhes" user "B.Adhesive")
		(13 "F.Paste" user "Package Geometry/Pastemask Top")
		(15 "B.Paste" user "Package Geometry/Pastemask Bottom")
		(5 "F.SilkS" user "Ref Des/Silkscreen Top")
		(7 "B.SilkS" user "Ref Des/Silkscreen Bottom")
		(1 "F.Mask" user "Board Geometry/Soldermask Top")
		(3 "B.Mask" user "Board Geometry/Soldermask Bottom")
		(17 "Dwgs.User" user "User.Drawings")
		(19 "Cmts.User" user "User.Comments")
		(21 "Eco1.User" user "User.Eco1")
		(23 "Eco2.User" user "User.Eco2")
		(25 "Edge.Cuts" user "Board Geometry/Outline")
		(27 "Margin" user)
		(31 "F.CrtYd" user "Package Geometry/Place Bound Top")
		(29 "B.CrtYd" user "Package Geometry/Place Bound Bottom")
		(35 "F.Fab" user "Ref Des/Assembly Top")
		(33 "B.Fab" user "Ref Des/Assembly Bottom")
	)
	(footprint ""
		(layer "F.Cu")
		(at 280.761948 -258.091686)
		(property "Reference" "J6"
			(at -3.683 -81.702148 0)
			(unlocked yes)
			(layer "F.SilkS")
			(effects
				(font
					(size 0.7874 0.5842)
					(thickness 0.1524)
				)
				(justify left)
			)
		)
		(property "Value" ""
			(at 0 0 0)
			(layer "F.Fab")
			(effects
				(font
					(size 1.27 1.27)
				)
			)
		)
		(duplicate_pad_numbers_are_jumpers no)
		(pad "1" smd rect
			(at -2.050034 -63.324994 270)
			(size 0.519938 1.4986)
			(layers "F.Cu" "F.Mask" "F.Paste")
			(net "P12V_S3_AUX_CPU0_NVDIMM")
		)
		(pad "2" smd rect
			(at -2.050034 -62.47511 270)
			(size 0.519938 1.4986)
			(layers "F.Cu" "F.Mask" "F.Paste")
			(net "TP_CHC_CPU0_DIMM2_FRU_0")
		)
		(pad "3" smd rect
			(at -2.050034 -61.624972 270)
			(size 0.519938 1.4986)
			(layers "F.Cu" "F.Mask" "F.Paste")
			(net "P3V3_AUX")
		)
		(pad "4" smd rect
			(at -2.050034 -60.775088 270)
			(size 0.519938 1.4986)
			(layers "F.Cu" "F.Mask" "F.Paste")
			(net "I3C_SPD_DDRABCD_CPU0_LVC1_SCL_5")
		)
		(pad "5" smd rect
			(at -2.050034 -59.92495 270)
			(size 0.519938 1.4986)
			(layers "F.Cu" "F.Mask" "F.Paste")
			(net "I3C_SPD_DDRABCD_CPU0_LVC1_SDA")
		)
		(pad "6" smd rect
			(at -2.050034 -59.075066 270)
			(size 0.519938 1.4986)
			(layers "F.Cu" "F.Mask" "F.Paste")
			(net "GND")
		)
		(pad "7" smd rect
			(at -2.050034 -58.224928 270)
			(size 0.519938 1.4986)
			(layers "F.Cu" "F.Mask" "F.Paste")
			(net "M_C_CPU0_SA_DQ<0>")
		)
		(pad "8" smd rect
			(at -2.050034 -57.375044 270)
			(size 0.519938 1.4986)
			(layers "F.Cu" "F.Mask" "F.Paste")
			(net "GND")
		)
		(pad "9" smd rect
			(at -2.050034 -56.524906 270)
			(size 0.519938 1.4986)
			(layers "F.Cu" "F.Mask" "F.Paste")
			(net "M_C_CPU0_SA_DQ<1>")
		)
		(pad "10" smd rect
			(at -2.050034 -55.675022 270)
			(size 0.519938 1.4986)
			(layers "F.Cu" "F.Mask" "F.Paste")
			(net "GND")
		)
		(pad "11" smd rect
			(at -2.050034 -54.824884 270)
			(size 0.519938 1.4986)
			(layers "F.Cu" "F.Mask" "F.Paste")
			(net "M_C_CPU0_SA_DQS_DP<0>")
		)
		(pad "12" smd rect
			(at -2.050034 -53.975 270)
			(size 0.519938 1.4986)
			(layers "F.Cu" "F.Mask" "F.Paste")
			(net "M_C_CPU0_SA_DQS_DN<0>")
		)
		(pad "13" smd rect
			(at -2.050034 -53.125116 270)
			(size 0.519938 1.4986)
			(layers "F.Cu" "F.Mask" "F.Paste")
			(net "GND")
		)
		(pad "14" smd rect
			(at -2.050034 -52.274978 270)
			(size 0.519938 1.4986)
			(layers "F.Cu" "F.Mask" "F.Paste")
			(net "M_C_CPU0_SA_DQ<4>")
		)
		(pad "15" smd rect
			(at -2.050034 -51.425094 270)
			(size 0.519938 1.4986)
			(layers "F.Cu" "F.Mask" "F.Paste")
			(net "GND")
		)
		(pad "16" smd rect
			(at -2.050034 -50.574956 270)
			(size 0.519938 1.4986)
			(layers "F.Cu" "F.Mask" "F.Paste")
			(net "M_C_CPU0_SA_DQ<5>")
		)
		(pad "17" smd rect
			(at -2.050034 -49.725072 270)
			(size 0.519938 1.4986)
			(layers "F.Cu" "F.Mask" "F.Paste")
			(net "GND")
		)
		(pad "18" smd rect
			(at -2.050034 -48.874934 270)
			(size 0.519938 1.4986)
			(layers "F.Cu" "F.Mask" "F.Paste")
			(net "M_C_CPU0_SA_DQ<8>")
		)
		(pad "19" smd rect
			(at -2.050034 -48.02505 270)
			(size 0.519938 1.4986)
			(layers "F.Cu" "F.Mask" "F.Paste")
			(net "GND")
		)
		(pad "20" smd rect
			(at -2.050034 -47.174912 270)
			(size 0.519938 1.4986)
			(layers "F.Cu" "F.Mask" "F.Paste")
			(net "M_C_CPU0_SA_DQ<9>")
		)
		(pad "21" smd rect
			(at -2.050034 -46.325028 270)
			(size 0.519938 1.4986)
			(layers "F.Cu" "F.Mask" "F.Paste")
			(net "GND")
		)
		(pad "22" smd rect
			(at -2.050034 -45.47489 270)
			(size 0.519938 1.4986)
			(layers "F.Cu" "F.Mask" "F.Paste")
			(net "M_C_CPU0_SA_DQS_DP<1>")
		)
		(pad "23" smd rect
			(at -2.050034 -44.625006 270)
			(size 0.519938 1.4986)
			(layers "F.Cu" "F.Mask" "F.Paste")
			(net "M_C_CPU0_SA_DQS_DN<1>")
		)
		(pad "24" smd rect
			(at -2.050034 -43.775122 270)
			(size 0.519938 1.4986)
			(layers "F.Cu" "F.Mask" "F.Paste")
			(net "GND")
		)
		(pad "25" smd rect
			(at -2.050034 -42.924984 270)
			(size 0.519938 1.4986)
			(layers "F.Cu" "F.Mask" "F.Paste")
			(net "M_C_CPU0_SA_DQ<12>")
		)
		(pad "26" smd rect
			(at -2.050034 -42.0751 270)
			(size 0.519938 1.4986)
			(layers "F.Cu" "F.Mask" "F.Paste")
			(net "GND")
		)
		(pad "27" smd rect
			(at -2.050034 -41.224962 270)
			(size 0.519938 1.4986)
			(layers "F.Cu" "F.Mask" "F.Paste")
			(net "M_C_CPU0_SA_DQ<13>")
		)
		(pad "28" smd rect
			(at -2.050034 -40.375078 270)
			(size 0.519938 1.4986)
			(layers "F.Cu" "F.Mask" "F.Paste")
			(net "GND")
		)
		(pad "29" smd rect
			(at -2.050034 -39.52494 270)
			(size 0.519938 1.4986)
			(layers "F.Cu" "F.Mask" "F.Paste")
			(net "M_C_CPU0_SA_DQ<16>")
		)
		(pad "30" smd rect
			(at -2.050034 -38.675056 270)
			(size 0.519938 1.4986)
			(layers "F.Cu" "F.Mask" "F.Paste")
			(net "GND")
		)
		(pad "31" smd rect
			(at -2.050034 -37.824918 270)
			(size 0.519938 1.4986)
			(layers "F.Cu" "F.Mask" "F.Paste")
			(net "M_C_CPU0_SA_DQ<17>")
		)
		(pad "32" smd rect
			(at -2.050034 -36.975034 270)
			(size 0.519938 1.4986)
			(layers "F.Cu" "F.Mask" "F.Paste")
			(net "GND")
		)
		(pad "33" smd rect
			(at -2.050034 -36.124896 270)
			(size 0.519938 1.4986)
			(layers "F.Cu" "F.Mask" "F.Paste")
			(net "M_C_CPU0_SA_DQS_DP<2>")
		)
		(pad "34" smd rect
			(at -2.050034 -35.275012 270)
			(size 0.519938 1.4986)
			(layers "F.Cu" "F.Mask" "F.Paste")
			(net "M_C_CPU0_SA_DQS_DN<2>")
		)
		(pad "35" smd rect
			(at -2.050034 -34.425128 270)
			(size 0.519938 1.4986)
			(layers "F.Cu" "F.Mask" "F.Paste")
			(net "GND")
		)
		(pad "36" smd rect
			(at -2.050034 -33.57499 270)
			(size 0.519938 1.4986)
			(layers "F.Cu" "F.Mask" "F.Paste")
			(net "M_C_CPU0_SA_DQ<20>")
		)
		(pad "37" smd rect
			(at -2.050034 -32.725106 270)
			(size 0.519938 1.4986)
			(layers "F.Cu" "F.Mask" "F.Paste")
			(net "GND")
		)
		(pad "38" smd rect
			(at -2.050034 -31.874968 270)
			(size 0.519938 1.4986)
			(layers "F.Cu" "F.Mask" "F.Paste")
			(net "M_C_CPU0_SA_DQ<21>")
		)
		(pad "39" smd rect
			(at -2.050034 -31.025084 270)
			(size 0.519938 1.4986)
			(layers "F.Cu" "F.Mask" "F.Paste")
			(net "GND")
		)
		(pad "40" smd rect
			(at -2.050034 -30.174946 270)
			(size 0.519938 1.4986)
			(layers "F.Cu" "F.Mask" "F.Paste")
			(net "M_C_CPU0_SA_DQ<24>")
		)
		(pad "41" smd rect
			(at -2.050034 -29.325062 270)
			(size 0.519938 1.4986)
			(layers "F.Cu" "F.Mask" "F.Paste")
			(net "GND")
		)
		(pad "42" smd rect
			(at -2.050034 -28.474924 270)
			(size 0.519938 1.4986)
			(layers "F.Cu" "F.Mask" "F.Paste")
			(net "M_C_CPU0_SA_DQ<25>")
		)
		(pad "43" smd rect
			(at -2.050034 -27.62504 270)
			(size 0.519938 1.4986)
			(layers "F.Cu" "F.Mask" "F.Paste")
			(net "GND")
		)
		(pad "44" smd rect
			(at -2.050034 -26.774902 270)
			(size 0.519938 1.4986)
			(layers "F.Cu" "F.Mask" "F.Paste")
			(net "M_C_CPU0_SA_DQS_DP<3>")
		)
		(pad "45" smd rect
			(at -2.050034 -25.925018 270)
			(size 0.519938 1.4986)
			(layers "F.Cu" "F.Mask" "F.Paste")
			(net "M_C_CPU0_SA_DQS_DN<3>")
		)
	)
)
